(kicad_pcb
	(version 20221018)
	(generator pcbnew)
	(general
    (thickness 1.562)
  )
	(paper "A4")
	(title_block
    (title "Thunderbolt PCIe Adaper")
    (date "2024-07-09")
    (rev "1.0.3")
    (comment 1 "www.antmicro.com")
    (comment 2 "Antmicro Ltd.")
		(comment 9 "footprints 89-96 of 271")
	)
	(layers
    (0 "F.Cu" signal)
    (1 "In1.Cu" signal)
    (2 "In2.Cu" signal)
    (3 "In3.Cu" signal)
    (4 "In4.Cu" signal)
    (31 "B.Cu" signal)
    (32 "B.Adhes" user "B.Adhesive")
    (33 "F.Adhes" user "F.Adhesive")
    (34 "B.Paste" user)
    (35 "F.Paste" user)
    (36 "B.SilkS" user "B.Silkscreen")
    (37 "F.SilkS" user "F.Silkscreen")
    (38 "B.Mask" user)
    (39 "F.Mask" user)
    (40 "Dwgs.User" user "User.Drawings")
    (41 "Cmts.User" user "User.Comments")
    (42 "Eco1.User" user "User.Eco1")
    (43 "Eco2.User" user "User.Eco2")
    (44 "Edge.Cuts" user)
    (45 "Margin" user)
    (46 "B.CrtYd" user "B.Courtyard")
    (47 "F.CrtYd" user "F.Courtyard")
    (48 "B.Fab" user)
    (49 "F.Fab" user)
  )
	(footprint "antmicro-footprints:R_0402_1005Metric" (layer "B.Cu")
    (at 108.915 84.68)
    (descr "Resistor SMD 0402")
    (tags "resistor SMD 0402")
    (property "Author" "Antmicro")
    (property "Current" "1A")
    (property "License" "Apache-2.0")
    (property "MPN" "ERJ2GE0R00X")
    (property "Manufacturer" "Panasonic")
    (property "Sheetfile" "power.kicad_sch")
    (property "Sheetname" "Power")
    (property "Tolerance" "")
    (property "Val" "0R")
    (property "ki_description" "SMD Chip Resistor, Jumper, 0 ohm, 100 mW, 0402 [1005 Metric], Thick Film, General Purpose")
    (property "ki_keywords" "0402, SMT, RESISTOR, PASSIVE")
    (attr smd)
    (fp_text reference "R27" (at -1.092 -5.686) (layer "B.SilkS")
        (effects (font (size 0.7 0.7) (thickness 0.15)) (justify right bottom mirror))
    )
    (fp_text value "R_0R_0402" (at -1.011843 -1.772047) (layer "B.Fab")
        (effects (font (size 0.7 0.7) (thickness 0.15)) (justify right bottom mirror))
    )
    (fp_text user "${REFERENCE}" (at -0.95 -3.168) (layer "B.Fab") hide
        (effects (font (size 0.7 0.7) (thickness 0.15)) (justify right bottom mirror))
    )
    (fp_text user "Author: Antmicro" (at -0.95 -4.169) (layer "B.Fab") hide
        (effects (font (size 0.7 0.7) (thickness 0.15)) (justify right bottom mirror))
    )
    (fp_text user "License: Apache-2.0" (at -0.95 -5.169) (layer "B.Fab") hide
        (effects (font (size 0.7 0.7) (thickness 0.15)) (justify right bottom mirror))
    )
    (fp_rect (start -0.925 0.47) (end 0.925 -0.47)
      (stroke (width 0.05) (type default)) (fill none) (layer "B.CrtYd"))
    (fp_rect (start -0.5 0.25) (end 0.5 -0.25)
      (stroke (width 0.15) (type solid)) (fill none) (layer "B.Fab"))
    (pad "1" smd roundrect (at -0.48 0) (size 0.59 0.64) (layers "B.Cu" "B.Paste" "B.Mask") (roundrect_rratio 0.25)
      (net 5 "Net-(U1-VREF)") (pintype "passive"))
    (pad "2" smd roundrect (at 0.48 0) (size 0.59 0.64) (layers "B.Cu" "B.Paste" "B.Mask") (roundrect_rratio 0.25)
      (net 159 "Net-(U1-SYNC{slash}MODE)") (pintype "passive"))
  )
	(footprint "antmicro-footprints:C_0402_1005Metric" (layer "B.Cu")
    (at 134.8 84.725)
    (descr "Capacitor SMD 0402")
    (tags "capacitor SMD 0402")
    (property "Author" "Antmicro")
    (property "Dielectric" "")
    (property "License" "Apache-2.0")
    (property "MPN" "C1005X6S1A105K050BC")
    (property "Manufacturer" "TDK")
    (property "Sheetfile" "tb-power.kicad_sch")
    (property "Sheetname" "Thunderbolt Controller - Power")
    (property "Val" "1u")
    (property "Voltage" "")
    (property "ki_description" "SMD Multilayer Ceramic Capacitor, 1 µF, 10 V, 0402 [1005 Metric], ± 10%, X6S, C")
    (property "ki_keywords" "0402, SMT, CAPACITOR, PASSIVE, CERAMIC, MLCC")
    (attr smd)
    (fp_text reference "C68" (at 17.6 7.649 180) (layer "B.SilkS")
        (effects (font (size 0.7 0.7) (thickness 0.15)) (justify left bottom mirror))
    )
    (fp_text value "C_1u_0402" (at -1.022927 -2.155213 180) (layer "B.Fab")
        (effects (font (size 0.7 0.7) (thickness 0.15)) (justify left bottom mirror))
    )
    (fp_text user "${REFERENCE}" (at -0.939 -4.599 180) (layer "B.Fab") hide
        (effects (font (size 0.7 0.7) (thickness 0.15)) (justify left bottom mirror))
    )
    (fp_text user "Author: Antmicro" (at -0.939 -3.399 180) (layer "B.Fab") hide
        (effects (font (size 0.7 0.7) (thickness 0.15)) (justify left bottom mirror))
    )
    (fp_text user "License: Apache-2.0" (at -0.939 -5.799 180) (layer "B.Fab") hide
        (effects (font (size 0.7 0.7) (thickness 0.15)) (justify left bottom mirror))
    )
    (fp_rect (start -0.925 0.47) (end 0.925 -0.47)
      (stroke (width 0.05) (type default)) (fill none) (layer "B.CrtYd"))
    (fp_line (start -0.494 -0.248) (end -0.494 0.25)
      (stroke (width 0.15) (type solid)) (layer "B.Fab"))
    (fp_line (start -0.494 0.25) (end 0.504 0.25)
      (stroke (width 0.15) (type solid)) (layer "B.Fab"))
    (fp_line (start 0.504 -0.248) (end -0.494 -0.248)
      (stroke (width 0.15) (type solid)) (layer "B.Fab"))
    (fp_line (start 0.504 0.25) (end 0.504 -0.248)
      (stroke (width 0.15) (type solid)) (layer "B.Fab"))
    (pad "1" smd roundrect (at -0.48 0) (size 0.59 0.64) (layers "B.Cu" "B.Paste" "B.Mask") (roundrect_rratio 0.25)
      (net 1 "GND") (pintype "passive"))
    (pad "2" smd roundrect (at 0.48 0) (size 0.59 0.64) (layers "B.Cu" "B.Paste" "B.Mask") (roundrect_rratio 0.25)
      (net 108 "Net-(C56-Pad2)") (pintype "passive"))
  )
	(footprint "antmicro-footprints:C_0402_1005Metric" (layer "B.Cu")
    (at 112.115 86.169999 90)
    (descr "Capacitor SMD 0402")
    (tags "capacitor SMD 0402")
    (property "Author" "Antmicro")
    (property "Dielectric" "")
    (property "License" "Apache-2.0")
    (property "MPN" "CGA2B3X7S2A472K050BB")
    (property "Manufacturer" "TDK")
    (property "Sheetfile" "power.kicad_sch")
    (property "Sheetname" "Power")
    (property "Val" "4n7")
    (property "Voltage" "")
    (property "ki_description" "SMD Multilayer Ceramic Capacitor, 4700 pF, 100 V, 0402 [1005 Metric], ± 10%, X7S, CGA")
    (property "ki_keywords" "0402, SMT, CAPACITOR, PASSIVE, CERAMIC, MLCC")
    (attr smd)
    (fp_text reference "C30" (at -2.984001 0.407 90) (layer "B.SilkS")
        (effects (font (size 0.7 0.7) (thickness 0.15)) (justify right bottom mirror))
    )
    (fp_text value "C_4n7_0402" (at -1.022927 -2.155213 90) (layer "B.Fab")
        (effects (font (size 0.7 0.7) (thickness 0.15)) (justify right bottom mirror))
    )
    (fp_text user "${REFERENCE}" (at -0.939 -4.599 90) (layer "B.Fab") hide
        (effects (font (size 0.7 0.7) (thickness 0.15)) (justify right bottom mirror))
    )
    (fp_text user "Author: Antmicro" (at -0.939 -3.399 90) (layer "B.Fab") hide
        (effects (font (size 0.7 0.7) (thickness 0.15)) (justify right bottom mirror))
    )
    (fp_text user "License: Apache-2.0" (at -0.939 -5.799 90) (layer "B.Fab") hide
        (effects (font (size 0.7 0.7) (thickness 0.15)) (justify right bottom mirror))
    )
    (fp_rect (start -0.925 0.47) (end 0.925 -0.47)
      (stroke (width 0.05) (type default)) (fill none) (layer "B.CrtYd"))
    (fp_line (start -0.494 -0.248) (end -0.494 0.25)
      (stroke (width 0.15) (type solid)) (layer "B.Fab"))
    (fp_line (start -0.494 0.25) (end 0.504 0.25)
      (stroke (width 0.15) (type solid)) (layer "B.Fab"))
    (fp_line (start 0.504 -0.248) (end -0.494 -0.248)
      (stroke (width 0.15) (type solid)) (layer "B.Fab"))
    (fp_line (start 0.504 0.25) (end 0.504 -0.248)
      (stroke (width 0.15) (type solid)) (layer "B.Fab"))
    (pad "1" smd roundrect (at -0.48 0 90) (size 0.59 0.64) (layers "B.Cu" "B.Paste" "B.Mask") (roundrect_rratio 0.25)
      (net 1 "GND") (pintype "passive"))
    (pad "2" smd roundrect (at 0.48 0 90) (size 0.59 0.64) (layers "B.Cu" "B.Paste" "B.Mask") (roundrect_rratio 0.25)
      (net 7 "Net-(C30-Pad2)") (pintype "passive"))
  )
	(footprint "antmicro-footprints:R_0402_1005Metric" (layer "B.Cu")
    (at 132.1 70.72 90)
    (descr "Resistor SMD 0402")
    (tags "resistor SMD 0402")
    (property "Author" "Antmicro")
    (property "License" "Apache-2.0")
    (property "MPN" "CR0402-FX-1002GLF")
    (property "Manufacturer" "Bourns")
    (property "Sheetfile" "tb.kicad_sch")
    (property "Sheetname" "TB Controller")
    (property "Tolerance" "1%")
    (property "Val" "10k")
    (property "ki_description" "SMD Chip Resistor, 10 kohm, ± 1%, 62.5 mW, 0402 [1005 Metric], Thick Film, General Purpose")
    (property "ki_keywords" "0402, SMT, RESISTOR, PASSIVE")
    (attr smd)
    (fp_text reference "R79" (at -0.908 0.361 270) (layer "B.SilkS")
        (effects (font (size 0.7 0.7) (thickness 0.15)) (justify left bottom mirror))
    )
    (fp_text value "R_10k_0402" (at -1.011843 -1.772047 270) (layer "B.Fab")
        (effects (font (size 0.7 0.7) (thickness 0.15)) (justify left bottom mirror))
    )
    (fp_text user "License: Apache-2.0" (at -0.95 -5.169 270) (layer "B.Fab") hide
        (effects (font (size 0.7 0.7) (thickness 0.15)) (justify left bottom mirror))
    )
    (fp_text user "${REFERENCE}" (at -0.95 -3.168 270) (layer "B.Fab") hide
        (effects (font (size 0.7 0.7) (thickness 0.15)) (justify left bottom mirror))
    )
    (fp_text user "Author: Antmicro" (at -0.95 -4.169 270) (layer "B.Fab") hide
        (effects (font (size 0.7 0.7) (thickness 0.15)) (justify left bottom mirror))
    )
    (fp_rect (start -0.925 0.47) (end 0.925 -0.47)
      (stroke (width 0.05) (type default)) (fill none) (layer "B.CrtYd"))
    (fp_rect (start -0.5 0.25) (end 0.5 -0.25)
      (stroke (width 0.15) (type solid)) (fill none) (layer "B.Fab"))
    (pad "1" smd roundrect (at -0.48 0 90) (size 0.59 0.64) (layers "B.Cu" "B.Paste" "B.Mask") (roundrect_rratio 0.25)
      (net 194 "Net-(U4C-GPIO_5)") (pintype "passive"))
    (pad "2" smd roundrect (at 0.48 0 90) (size 0.59 0.64) (layers "B.Cu" "B.Paste" "B.Mask") (roundrect_rratio 0.25)
      (net 1 "GND") (pintype "passive"))
  )
	(footprint "antmicro-footprints:C_0402_1005Metric" (layer "B.Cu")
    (at 126.5 92.65 -90)
    (descr "Capacitor SMD 0402")
    (tags "capacitor SMD 0402")
    (property "Author" "Antmicro")
    (property "Dielectric" "")
    (property "License" "Apache-2.0")
    (property "MPN" "CC0402KRX5R6BB224")
    (property "Manufacturer" "YAGEO")
    (property "Sheetfile" "tb.kicad_sch")
    (property "Sheetname" "TB Controller")
    (property "Val" "220n")
    (property "Voltage" "")
    (property "ki_description" "SMD Multilayer Ceramic Capacitor, 0.22 µF, 10 V, 0402 [1005 Metric], ± 10%, X5R, CC Series")
    (property "ki_keywords" "0402, SMT, CAPACITOR, PASSIVE, MLCC, CERAMIC")
    (attr smd)
    (fp_text reference "C109" (at -3.877 -0.47 90) (layer "B.SilkS")
        (effects (font (size 0.7 0.7) (thickness 0.15)) (justify left bottom mirror))
    )
    (fp_text value "C_220n_0402" (at -1.022927 -2.155213 90) (layer "B.Fab")
        (effects (font (size 0.7 0.7) (thickness 0.15)) (justify left bottom mirror))
    )
    (fp_text user "${REFERENCE}" (at -0.939 -4.599 90) (layer "B.Fab") hide
        (effects (font (size 0.7 0.7) (thickness 0.15)) (justify left bottom mirror))
    )
    (fp_text user "License: Apache-2.0" (at -0.939 -5.799 90) (layer "B.Fab") hide
        (effects (font (size 0.7 0.7) (thickness 0.15)) (justify left bottom mirror))
    )
    (fp_text user "Author: Antmicro" (at -0.939 -3.399 90) (layer "B.Fab") hide
        (effects (font (size 0.7 0.7) (thickness 0.15)) (justify left bottom mirror))
    )
    (fp_rect (start -0.925 0.47) (end 0.925 -0.47)
      (stroke (width 0.05) (type default)) (fill none) (layer "B.CrtYd"))
    (fp_line (start -0.494 -0.248) (end -0.494 0.25)
      (stroke (width 0.15) (type solid)) (layer "B.Fab"))
    (fp_line (start -0.494 0.25) (end 0.504 0.25)
      (stroke (width 0.15) (type solid)) (layer "B.Fab"))
    (fp_line (start 0.504 -0.248) (end -0.494 -0.248)
      (stroke (width 0.15) (type solid)) (layer "B.Fab"))
    (fp_line (start 0.504 0.25) (end 0.504 -0.248)
      (stroke (width 0.15) (type solid)) (layer "B.Fab"))
    (pad "1" smd roundrect (at -0.48 0 270) (size 0.59 0.64) (layers "B.Cu" "B.Paste" "B.Mask") (roundrect_rratio 0.25)
      (net 80 "/TB Controller/TX0_P") (pintype "passive"))
    (pad "2" smd roundrect (at 0.48 0 270) (size 0.59 0.64) (layers "B.Cu" "B.Paste" "B.Mask") (roundrect_rratio 0.25)
      (net 28 "PCIE_TX0_P") (pintype "passive"))
  )
	(footprint "antmicro-footprints:C_0402_1005Metric" (layer "B.Cu")
    (at 123 79.2)
    (descr "Capacitor SMD 0402")
    (tags "capacitor SMD 0402")
    (property "Author" "Antmicro")
    (property "Dielectric" "X5R")
    (property "License" "Apache-2.0")
    (property "MPN" "GRM155R61H104KE14D")
    (property "Manufacturer" "Murata")
    (property "Sheetfile" "tb.kicad_sch")
    (property "Sheetname" "TB Controller")
    (property "Val" "100n")
    (property "Voltage" "50V")
    (property "ki_description" "SMD Multilayer Ceramic Capacitor, 0.1 µF, 50 V, 0402 [1005 Metric], ± 10%, X5R, GRM Series")
    (property "ki_keywords" "0402, SMT, CAPACITOR, PASSIVE, CERAMIC, MLCC")
    (attr smd)
    (fp_text reference "C115" (at 1.079 1.445 180) (layer "B.SilkS")
        (effects (font (size 0.7 0.7) (thickness 0.15)) (justify left bottom mirror))
    )
    (fp_text value "C_100n_0402" (at -1.022927 -2.155213 180) (layer "B.Fab")
        (effects (font (size 0.7 0.7) (thickness 0.15)) (justify left bottom mirror))
    )
    (fp_text user "License: Apache-2.0" (at -0.939 -5.799 180) (layer "B.Fab") hide
        (effects (font (size 0.7 0.7) (thickness 0.15)) (justify left bottom mirror))
    )
    (fp_text user "Author: Antmicro" (at -0.939 -3.399 180) (layer "B.Fab") hide
        (effects (font (size 0.7 0.7) (thickness 0.15)) (justify left bottom mirror))
    )
    (fp_text user "${REFERENCE}" (at -0.939 -4.599 180) (layer "B.Fab") hide
        (effects (font (size 0.7 0.7) (thickness 0.15)) (justify left bottom mirror))
    )
    (fp_rect (start -0.925 0.47) (end 0.925 -0.47)
      (stroke (width 0.05) (type default)) (fill none) (layer "B.CrtYd"))
    (fp_line (start -0.494 -0.248) (end -0.494 0.25)
      (stroke (width 0.15) (type solid)) (layer "B.Fab"))
    (fp_line (start -0.494 0.25) (end 0.504 0.25)
      (stroke (width 0.15) (type solid)) (layer "B.Fab"))
    (fp_line (start 0.504 -0.248) (end -0.494 -0.248)
      (stroke (width 0.15) (type solid)) (layer "B.Fab"))
    (fp_line (start 0.504 0.25) (end 0.504 -0.248)
      (stroke (width 0.15) (type solid)) (layer "B.Fab"))
    (pad "1" smd roundrect (at -0.48 0) (size 0.59 0.64) (layers "B.Cu" "B.Paste" "B.Mask") (roundrect_rratio 0.25)
      (net 1 "GND") (pintype "passive"))
    (pad "2" smd roundrect (at 0.48 0) (size 0.59 0.64) (layers "B.Cu" "B.Paste" "B.Mask") (roundrect_rratio 0.25)
      (net 2 "3V3_SYS") (pintype "passive"))
  )
	(footprint "antmicro-footprints:C_0402_1005Metric" (layer "B.Cu")
    (at 155.08 81.74 180)
    (descr "Capacitor SMD 0402")
    (tags "capacitor SMD 0402")
    (property "Author" "Antmicro")
    (property "Dielectric" "")
    (property "License" "Apache-2.0")
    (property "MPN" "CC0402KRX5R6BB224")
    (property "Manufacturer" "YAGEO")
    (property "Sheetfile" "tb.kicad_sch")
    (property "Sheetname" "TB Controller")
    (property "Val" "220n")
    (property "Voltage" "")
    (property "ki_description" "SMD Multilayer Ceramic Capacitor, 0.22 µF, 10 V, 0402 [1005 Metric], ± 10%, X5R, CC Series")
    (property "ki_keywords" "0402, SMT, CAPACITOR, PASSIVE, MLCC, CERAMIC")
    (attr smd)
    (fp_text reference "C99" (at 1.034 -0.431) (layer "B.SilkS")
        (effects (font (size 0.7 0.7) (thickness 0.15)) (justify left bottom mirror))
    )
    (fp_text value "C_220n_0402" (at -1.022927 -2.155213) (layer "B.Fab")
        (effects (font (size 0.7 0.7) (thickness 0.15)) (justify left bottom mirror))
    )
    (fp_text user "Author: Antmicro" (at -0.939 -3.399) (layer "B.Fab") hide
        (effects (font (size 0.7 0.7) (thickness 0.15)) (justify left bottom mirror))
    )
    (fp_text user "License: Apache-2.0" (at -0.939 -5.799) (layer "B.Fab") hide
        (effects (font (size 0.7 0.7) (thickness 0.15)) (justify left bottom mirror))
    )
    (fp_text user "${REFERENCE}" (at -0.939 -4.599) (layer "B.Fab") hide
        (effects (font (size 0.7 0.7) (thickness 0.15)) (justify left bottom mirror))
    )
    (fp_rect (start -0.925 0.47) (end 0.925 -0.47)
      (stroke (width 0.05) (type default)) (fill none) (layer "B.CrtYd"))
    (fp_line (start -0.494 -0.248) (end -0.494 0.25)
      (stroke (width 0.15) (type solid)) (layer "B.Fab"))
    (fp_line (start -0.494 0.25) (end 0.504 0.25)
      (stroke (width 0.15) (type solid)) (layer "B.Fab"))
    (fp_line (start 0.504 -0.248) (end -0.494 -0.248)
      (stroke (width 0.15) (type solid)) (layer "B.Fab"))
    (fp_line (start 0.504 0.25) (end 0.504 -0.248)
      (stroke (width 0.15) (type solid)) (layer "B.Fab"))
    (pad "1" smd roundrect (at -0.48 0 180) (size 0.59 0.64) (layers "B.Cu" "B.Paste" "B.Mask") (roundrect_rratio 0.25)
      (net 12 "TB_TX0_P") (pintype "passive"))
    (pad "2" smd roundrect (at 0.48 0 180) (size 0.59 0.64) (layers "B.Cu" "B.Paste" "B.Mask") (roundrect_rratio 0.25)
      (net 13 "/TB Controller/PA_TX0_P") (pintype "passive"))
  )
	(footprint "antmicro-footprints:C_0402_1005Metric" (layer "B.Cu")
    (at 135.115 58.1 180)
    (descr "Capacitor SMD 0402")
    (tags "capacitor SMD 0402")
    (property "Author" "Antmicro")
    (property "Dielectric" "X5R")
    (property "License" "Apache-2.0")
    (property "MPN" "GRM155R61H104KE14D")
    (property "Manufacturer" "Murata")
    (property "Sheetfile" "tb.kicad_sch")
    (property "Sheetname" "TB Controller")
    (property "Val" "100n")
    (property "Voltage" "50V")
    (property "ki_description" "SMD Multilayer Ceramic Capacitor, 0.1 µF, 50 V, 0402 [1005 Metric], ± 10%, X5R, GRM Series")
    (property "ki_keywords" "0402, SMT, CAPACITOR, PASSIVE, CERAMIC, MLCC")
    (attr smd)
    (fp_text reference "C101" (at 1.003 -0.447) (layer "B.SilkS")
        (effects (font (size 0.7 0.7) (thickness 0.15)) (justify left bottom mirror))
    )
    (fp_text value "C_100n_0402" (at -1.022927 -2.155213) (layer "B.Fab")
        (effects (font (size 0.7 0.7) (thickness 0.15)) (justify left bottom mirror))
    )
    (fp_text user "License: Apache-2.0" (at -0.939 -5.799) (layer "B.Fab") hide
        (effects (font (size 0.7 0.7) (thickness 0.15)) (justify left bottom mirror))
    )
    (fp_text user "${REFERENCE}" (at -0.939 -4.599) (layer "B.Fab") hide
        (effects (font (size 0.7 0.7) (thickness 0.15)) (justify left bottom mirror))
    )
    (fp_text user "Author: Antmicro" (at -0.939 -3.399) (layer "B.Fab") hide
        (effects (font (size 0.7 0.7) (thickness 0.15)) (justify left bottom mirror))
    )
    (fp_rect (start -0.925 0.47) (end 0.925 -0.47)
      (stroke (width 0.05) (type default)) (fill none) (layer "B.CrtYd"))
    (fp_line (start -0.494 -0.248) (end -0.494 0.25)
      (stroke (width 0.15) (type solid)) (layer "B.Fab"))
    (fp_line (start -0.494 0.25) (end 0.504 0.25)
      (stroke (width 0.15) (type solid)) (layer "B.Fab"))
    (fp_line (start 0.504 -0.248) (end -0.494 -0.248)
      (stroke (width 0.15) (type solid)) (layer "B.Fab"))
    (fp_line (start 0.504 0.25) (end 0.504 -0.248)
      (stroke (width 0.15) (type solid)) (layer "B.Fab"))
    (pad "1" smd roundrect (at -0.48 0 180) (size 0.59 0.64) (layers "B.Cu" "B.Paste" "B.Mask") (roundrect_rratio 0.25)
      (net 16 "AUX_P") (pintype "passive"))
    (pad "2" smd roundrect (at 0.48 0 180) (size 0.59 0.64) (layers "B.Cu" "B.Paste" "B.Mask") (roundrect_rratio 0.25)
      (net 86 "/TB Controller/PA_AUX_P") (pintype "passive"))
  )
)
